# S9S_MB_2U (Grand Teton) — schematic netlist excerpt (pin names and nets, part order shuffled) for the footprints in the layout excerpt that follows; sources: Cadence DE-HDL packaged netlist, KiCad conversion of 03242023_DA0F0TMBIJ0_F0T_Motherboard_J_brd_V01_OCP.brd

J6  SCONN288_ADR50017P087CC  SCONN288_ADR50017-P087CC IO  pkg DDR288S_1-1VXB  page 87
  VIN_BULK0  = P12V_S3_AUX_CPU0_NVDIMM
  RFU0  = TP_CHC_CPU0_DIMM2_FRU_0
  VIN_MGMT  = P3V3_AUX
  HSCL  = I3C_SPD_DDRABCD_CPU0_LVC1_SCL_5
  HSDA  = I3C_SPD_DDRABCD_CPU0_LVC1_SDA
  VSS0  = GND
  DQ0_A  = M_C_CPU0_SA_DQ<0>
  VSS1  = GND
  DQ1_A  = M_C_CPU0_SA_DQ<1>
  VSS2  = GND
  DQS0_A_T  = M_C_CPU0_SA_DQS_DP<0>
  DQS0_A_C  = M_C_CPU0_SA_DQS_DN<0>
  VSS3  = GND
  DQ4_A  = M_C_CPU0_SA_DQ<4>
  VSS4  = GND
  DQ5_A  = M_C_CPU0_SA_DQ<5>
  VSS5  = GND
  DQ8_A  = M_C_CPU0_SA_DQ<8>
  VSS6  = GND
  DQ9_A  = M_C_CPU0_SA_DQ<9>
  VSS7  = GND
  DQS1_A_T  = M_C_CPU0_SA_DQS_DP<1>
  DQS1_A_C  = M_C_CPU0_SA_DQS_DN<1>
  VSS8  = GND
  DQ12_A  = M_C_CPU0_SA_DQ<12>
  VSS9  = GND
  DQ13_A  = M_C_CPU0_SA_DQ<13>
  VSS10  = GND
  DQ16_A  = M_C_CPU0_SA_DQ<16>
  VSS11  = GND
  DQ17_A  = M_C_CPU0_SA_DQ<17>
  VSS12  = GND
  DQS2_A_T  = M_C_CPU0_SA_DQS_DP<2>
  DQS2_A_C  = M_C_CPU0_SA_DQS_DN<2>
  VSS13  = GND
  DQ20_A  = M_C_CPU0_SA_DQ<20>
  VSS14  = GND
  DQ21_A  = M_C_CPU0_SA_DQ<21>
  VSS15  = GND
  DQ24_A  = M_C_CPU0_SA_DQ<24>
  VSS16  = GND
  DQ25_A  = M_C_CPU0_SA_DQ<25>
  VSS17  = GND
  DQS3_A_T  = M_C_CPU0_SA_DQS_DP<3>
  DQS3_A_C  = M_C_CPU0_SA_DQS_DN<3>
  VSS18  = GND
  DQ28_A  = M_C_CPU0_SA_DQ<28>
  VSS19  = GND
  DQ29_A  = M_C_CPU0_SA_DQ<29>
  VSS20  = GND
  CB0_A  = M_C_CPU0_SA_CB<0>
  VSS21  = GND
  CB1_A  = M_C_CPU0_SA_CB<1>
  VSS22  = GND
  DQS4_A_T  = M_C_CPU0_SA_DQS_DP<4>
  DQS4_A_C  = M_C_CPU0_SA_DQS_DN<4>
  VSS23  = GND
  CB4_A  = M_C_CPU0_SA_CB<4>
  VSS24  = GND
  CB5_A  = M_C_CPU0_SA_CB<5>
  VSS25  = GND
  ALERT_N  = M_C_CPU0_ALERT_N
  VSS26  = GND
  CS0_A_N  = M_C_CPU0_SA_CS_N<2>
  VSS27  = GND
  CA0_A  = M_C_CPU0_SA_CA<0>
  VSS28  = GND
  CA2_A  = M_C_CPU0_SA_CA<2>
  VSS29  = GND
  CA4_A  = M_C_CPU0_SA_CA<4>
  VSS30  = GND
  CA6_A  = M_C_CPU0_SA_CA<6>
  VSS31  = GND
  PAR_A  = M_C_CPU0_SA_PAR
  VSS32  = GND
  CA0_B  = M_C_CPU0_SB_CA<0>
  VSS33  = GND
  CA2_B  = M_C_CPU0_SB_CA<2>
  VSS34  = GND
  CA4_B  = M_C_CPU0_SB_CA<4>
  VSS35  = GND
  CA6_B  = M_C_CPU0_SB_CA<6>
  VSS36  = GND
  CS0_B_N  = M_C_CPU0_SB_CS_N<2>
  VSS37  = GND
  \lbd||rsp_a_n\  = M_C_CPU0_SA_RSP<1>
  \lbs||rsp_b_n\  = M_C_CPU0_SB_RSP<1>
  VSS38  = GND
  CB4_B  = M_C_CPU0_SB_CB<4>
  VSS39  = GND
  CB5_B  = M_C_CPU0_SB_CB<5>
  VSS40  = GND
  \dqs9_b_t||tdqs9_b_t||dbi4_b_n\  = M_C_CPU0_SB_DQS_DP<9>
  \dqs9_b_c||tdqs9_b_c\  = M_C_CPU0_SB_DQS_DN<9>
  VSS41  = GND
  CB0_B  = M_C_CPU0_SB_CB<0>
  VSS42  = GND
  CB1_B  = M_C_CPU0_SB_CB<1>
  VSS43  = GND
  DQ0_B  = M_C_CPU0_SB_DQ<0>
  VSS44  = GND
  DQ1_B  = M_C_CPU0_SB_DQ<1>
  VSS45  = GND
  DQS0_B_T  = M_C_CPU0_SB_DQS_DP<0>
  DQS0_B_C  = M_C_CPU0_SB_DQS_DN<0>
  VSS46  = GND
  DQ4_B  = M_C_CPU0_SB_DQ<4>
  VSS47  = GND
  DQ5_B  = M_C_CPU0_SB_DQ<5>
  VSS48  = GND
  DQ8_B  = M_C_CPU0_SB_DQ<8>
  VSS49  = GND
  DQ9_B  = M_C_CPU0_SB_DQ<9>
  VSS50  = GND
  DQS1_B_T  = M_C_CPU0_SB_DQS_DP<1>
  DQS1_B_C  = M_C_CPU0_SB_DQS_DN<1>
  VSS51  = GND
  DQ12_B  = M_C_CPU0_SB_DQ<12>
  VSS52  = GND
  DQ13_B  = M_C_CPU0_SB_DQ<13>
  VSS53  = GND
  DQ16_B  = M_C_CPU0_SB_DQ<16>
  VSS54  = GND
  DQ17_B  = M_C_CPU0_SB_DQ<17>
  VSS55  = GND
  DQS2_B_T  = M_C_CPU0_SB_DQS_DP<2>
  DQS2_B_C  = M_C_CPU0_SB_DQS_DN<2>
  VSS56  = GND
  DQ20_B  = M_C_CPU0_SB_DQ<20>
  VSS57  = GND
  DQ21_B  = M_C_CPU0_SB_DQ<21>
  VSS58  = GND
  DQ24_B  = M_C_CPU0_SB_DQ<24>
  VSS59  = GND
  DQ25_B  = M_C_CPU0_SB_DQ<25>
  VSS60  = GND
  DQS3_B_T  = M_C_CPU0_SB_DQS_DP<3>
  DQS3_B_C  = M_C_CPU0_SB_DQS_DN<3>
  VSS61  = GND
  DQ28_B  = M_C_CPU0_SB_DQ<28>
  VSS62  = GND
  DQ29_B  = M_C_CPU0_SB_DQ<29>
  VSS63  = GND
  RFU1  = TP_CHC_CPU0_DIMM2_FRU_1
  VIN_BULK1  = P12V_S3_AUX_CPU0_NVDIMM
  VIN_BULK2  = P12V_S3_AUX_CPU0_NVDIMM
  \pwr_good||fail_n\  = PWRGD_CHC_CPU0_DIMM2
  HSA  = PD_CHC_CPU0_DIMM2_SAA
  RFU2  = TP_CHC_CPU0_DIMM2_FRU_2
  RFU3  = TP_CHC_CPU0_DIMM2_FRU_3
  VSS64  = GND
  DQ2_A  = M_C_CPU0_SA_DQ<2>
  VSS65  = GND
  DQ3_A  = M_C_CPU0_SA_DQ<3>
  VSS66  = GND
  \dqs5_a_c||tdqs5_a_c||dqs5_a_t||tdqs5_a_t\  = M_C_CPU0_SA_DQS_DN<5>
  \dqs5_a_t||tdqs5_a_t\  = M_C_CPU0_SA_DQS_DP<5>
  VSS67  = GND
  DQ6_A  = M_C_CPU0_SA_DQ<6>
  VSS68  = GND
  DQ7_A  = M_C_CPU0_SA_DQ<7>
  VSS69  = GND
  DQ10_A  = M_C_CPU0_SA_DQ<10>
  VSS70  = GND
  DQ11_A  = M_C_CPU0_SA_DQ<11>
  VSS71  = GND
  \dqs6_a_c||tdqs6_a_c||dqs6_a_t||tdqs6_a_t\  = M_C_CPU0_SA_DQS_DN<6>
  \dqs6_a_t||tdqs6_a_t\  = M_C_CPU0_SA_DQS_DP<6>
  VSS72  = GND
  DQ14_A  = M_C_CPU0_SA_DQ<14>
  VSS73  = GND
  DQ15_A  = M_C_CPU0_SA_DQ<15>
  VSS74  = GND
  DQ18_A  = M_C_CPU0_SA_DQ<18>
  VSS75  = GND
  DQ19_A  = M_C_CPU0_SA_DQ<19>
  VSS76  = GND
  \dqs7_a_c||tdqs7_a_c\  = M_C_CPU0_SA_DQS_DN<7>
  \dqs7_a_t||tdqs7_a_t\  = M_C_CPU0_SA_DQS_DP<7>
  VSS77  = GND
  DQ22_A  = M_C_CPU0_SA_DQ<22>
  VSS78  = GND
  DQ23_A  = M_C_CPU0_SA_DQ<23>
  VSS79  = GND
  DQ26_A  = M_C_CPU0_SA_DQ<26>
  VSS80  = GND
  DQ27_A  = M_C_CPU0_SA_DQ<27>
  VSS81  = GND
  \dqs8_a_c||tdqs8_a_c\  = M_C_CPU0_SA_DQS_DN<8>
  \dqs8_a_t||tdqs8_a_t\  = M_C_CPU0_SA_DQS_DP<8>
  VSS82  = GND
  DQ30_A  = M_C_CPU0_SA_DQ<30>
  VSS83  = GND
  DQ31_A  = M_C_CPU0_SA_DQ<31>
  VSS84  = GND
  CB2_A  = M_C_CPU0_SA_CB<2>
  VSS85  = GND
  CB3_A  = M_C_CPU0_SA_CB<3>
  VSS86  = GND
  \dqs9_a_c||tdqs9_a_c\  = M_C_CPU0_SA_DQS_DN<9>
  \dqs9_a_t||tdqs9_a_t\  = M_C_CPU0_SA_DQS_DP<9>
  VSS87  = GND
  CB6_A  = M_C_CPU0_SA_CB<6>
  VSS88  = GND
  CB7_A  = M_C_CPU0_SA_CB<7>
  VSS89  = GND
  RESET_N  = RST_M_CD_CPU0_FPGA_N
  VSS90  = GND
  CS1_A_N  = M_C_CPU0_SA_CS_N<3>
  VSS91  = GND
  CA1_A  = M_C_CPU0_SA_CA<1>
  VSS92  = GND
  CA3_A  = M_C_CPU0_SA_CA<3>
  VSS93  = GND
  CA5_A  = M_C_CPU0_SA_CA<5>
  VSS94  = GND
  CK_T  = M_C_CPU0_CLK_DP<1>
  CK_C  = M_C_CPU0_CLK_DN<1>
  VSS95  = GND
  RFU4  = TP_CHC_CPU0_DIMM2_FRU_4
  CA1_B  = M_C_CPU0_SB_CA<1>
  VSS96  = GND
  CA3_B  = M_C_CPU0_SB_CA<3>
  VSS97  = GND
  CA5_B  = M_C_CPU0_SB_CA<5>
  VSS98  = GND
  PAR_B  = M_C_CPU0_SB_PAR
  VSS99  = GND
  CS1_B_N  = M_C_CPU0_SB_CS_N<3>
  VSS100  = GND
  RFU5  = TP_CHC_CPU0_DIMM2_FRU_5
  RFU6  = TP_CHC_CPU0_DIMM2_FRU_6
  VSS101  = GND
  CB6_B  = M_C_CPU0_SB_CB<6>
  VSS102  = GND
  CB7_B  = M_C_CPU0_SB_CB<7>
  VSS103  = GND
  DQS4_B_C  = M_C_CPU0_SB_DQS_DN<4>
  DQS4_B_T  = M_C_CPU0_SB_DQS_DP<4>
  VSS104  = GND
  CB2_B  = M_C_CPU0_SB_CB<2>
  VSS105  = GND
  CB3_B  = M_C_CPU0_SB_CB<3>
  VSS106  = GND
  DQ2_B  = M_C_CPU0_SB_DQ<2>
  VSS107  = GND
  DQ3_B  = M_C_CPU0_SB_DQ<3>
  VSS108  = GND
  \dqs5_b_c||tdqs5_b_c\  = M_C_CPU0_SB_DQS_DN<5>
  \dqs5_b_t||tdqs5_b_t\  = M_C_CPU0_SB_DQS_DP<5>
  VSS109  = GND
  DQ6_B  = M_C_CPU0_SB_DQ<6>
  VSS110  = GND
  DQ7_B  = M_C_CPU0_SB_DQ<7>
  VSS111  = GND
  DQ10_B  = M_C_CPU0_SB_DQ<10>
  VSS112  = GND
  DQ11_B  = M_C_CPU0_SB_DQ<11>
  VSS113  = GND
  \dqs6_b_c||tdqs6_b_c\  = M_C_CPU0_SB_DQS_DN<6>
  \dqs6_b_t||tdqs6_b_t\  = M_C_CPU0_SB_DQS_DP<6>
  VSS114  = GND
  DQ14_B  = M_C_CPU0_SB_DQ<14>
  VSS115  = GND
  DQ15_B  = M_C_CPU0_SB_DQ<15>
  VSS116  = GND
  DQ18_B  = M_C_CPU0_SB_DQ<18>
  VSS117  = GND
  DQ19_B  = M_C_CPU0_SB_DQ<19>
  VSS118  = GND
  \dqs7_b_c||tdqs7_b_c\  = M_C_CPU0_SB_DQS_DN<7>
  \dqs7_b_t||tdqs7_b_t\  = M_C_CPU0_SB_DQS_DP<7>
  VSS119  = GND
  DQ22_B  = M_C_CPU0_SB_DQ<22>
  VSS120  = GND
  DQ23_B  = M_C_CPU0_SB_DQ<23>
  VSS121  = GND
  DQ26_B  = M_C_CPU0_SB_DQ<26>
  VSS122  = GND
  DQ27_B  = M_C_CPU0_SB_DQ<27>
  VSS123  = GND
  \dqs8_b_c||tdqs8_b_c\  = M_C_CPU0_SB_DQS_DN<8>
  \dqs8_b_t||tdqs8_b_t\  = M_C_CPU0_SB_DQS_DP<8>
  VSS124  = GND
  DQ30_B  = M_C_CPU0_SB_DQ<30>
  VSS125  = GND
  DQ31_B  = M_C_CPU0_SB_DQ<31>
  VSS126  = GND
  G1  = GND
  G2  = GND
  G3  = GND

(kicad_pcb
	(version 20260206)
	(generator "pcbnew")
	(generator_version "10.0")
	(general
		(thickness 1.6)
		(legacy_teardrops no)
	)
	(paper "A4")
	(title_block
		(title "03242023_DA0F0TMBIJ0_F0T_Motherboard_J_brd_V01_OCP.brd")
		(comment 1 "Grand Teton / footprint 3553 of 6105 (J6), pads 275-291 of 291")
	)
	(layers
		(0 "F.Cu" signal "TOP")
		(4 "In1.Cu" signal "GND")
		(6 "In2.Cu" signal "IN1")
		(8 "In3.Cu" signal "GND1")
		(10 "In4.Cu" signal "IN2")
		(12 "In5.Cu" signal "GND2")
		(14 "In6.Cu" signal "IN3")
		(16 "In7.Cu" signal "GND3")
		(18 "In8.Cu" signal "VCC")
		(20 "In9.Cu" signal "VCC1")
		(22 "In10.Cu" signal "GND4")
		(24 "In11.Cu" signal "IN4")
		(26 "In12.Cu" signal "GND5")
		(28 "In13.Cu" signal "IN5")
		(30 "In14.Cu" signal "GND6")
		(32 "In15.Cu" signal "IN6")
		(34 "In16.Cu" signal "GND7")
		(2 "B.Cu" signal "BOTTOM")
		(9 "F.Adhes" user "F.Adhesive")
		(11 "B.Adhes" user "B.Adhesive")
		(13 "F.Paste" user "Package Geometry/Pastemask Top")
		(15 "B.Paste" user "Package Geometry/Pastemask Bottom")
		(5 "F.SilkS" user "Ref Des/Silkscreen Top")
		(7 "B.SilkS" user "Ref Des/Silkscreen Bottom")
		(1 "F.Mask" user "Board Geometry/Soldermask Top")
		(3 "B.Mask" user "Board Geometry/Soldermask Bottom")
		(17 "Dwgs.User" user "User.Drawings")
		(19 "Cmts.User" user "User.Comments")
		(21 "Eco1.User" user "User.Eco1")
		(23 "Eco2.User" user "User.Eco2")
		(25 "Edge.Cuts" user "Board Geometry/Outline")
		(27 "Margin" user)
		(31 "F.CrtYd" user "Package Geometry/Place Bound Top")
		(29 "B.CrtYd" user "Package Geometry/Place Bound Bottom")
		(35 "F.Fab" user "Ref Des/Assembly Top")
		(33 "B.Fab" user "Ref Des/Assembly Bottom")
	)
	(footprint ""
		(layer "F.Cu")
		(at 280.761948 -258.091686)
		(property "Reference" "J6"
			(at -3.683 -81.702148 0)
			(unlocked yes)
			(layer "F.SilkS")
			(effects
				(font
					(size 0.7874 0.5842)
					(thickness 0.1524)
				)
				(justify left)
			)
		)
		(property "Value" ""
			(at 0 0 0)
			(layer "F.Fab")
			(effects
				(font
					(size 1.27 1.27)
				)
			)
		)
		(duplicate_pad_numbers_are_jumpers no)
		(pad "275" smd rect
			(at 2.050034 52.274978 270)
			(size 0.519938 1.4986)
			(layers "F.Cu" "F.Mask" "F.Paste")
			(net "GND")
		)
		(pad "276" smd rect
			(at 2.050034 53.125116 270)
			(size 0.519938 1.4986)
			(layers "F.Cu" "F.Mask" "F.Paste")
			(net "M_C_CPU0_SB_DQ<23>")
		)
		(pad "277" smd rect
			(at 2.050034 53.975 270)
			(size 0.519938 1.4986)
			(layers "F.Cu" "F.Mask" "F.Paste")
			(net "GND")
		)
		(pad "278" smd rect
			(at 2.050034 54.824884 270)
			(size 0.519938 1.4986)
			(layers "F.Cu" "F.Mask" "F.Paste")
			(net "M_C_CPU0_SB_DQ<26>")
		)
		(pad "279" smd rect
			(at 2.050034 55.675022 270)
			(size 0.519938 1.4986)
			(layers "F.Cu" "F.Mask" "F.Paste")
			(net "GND")
		)
		(pad "280" smd rect
			(at 2.050034 56.524906 270)
			(size 0.519938 1.4986)
			(layers "F.Cu" "F.Mask" "F.Paste")
			(net "M_C_CPU0_SB_DQ<27>")
		)
		(pad "281" smd rect
			(at 2.050034 57.375044 270)
			(size 0.519938 1.4986)
			(layers "F.Cu" "F.Mask" "F.Paste")
			(net "GND")
		)
		(pad "282" smd rect
			(at 2.050034 58.224928 270)
			(size 0.519938 1.4986)
			(layers "F.Cu" "F.Mask" "F.Paste")
			(net "M_C_CPU0_SB_DQS_DN<8>")
		)
		(pad "283" smd rect
			(at 2.050034 59.075066 270)
			(size 0.519938 1.4986)
			(layers "F.Cu" "F.Mask" "F.Paste")
			(net "M_C_CPU0_SB_DQS_DP<8>")
		)
		(pad "284" smd rect
			(at 2.050034 59.92495 270)
			(size 0.519938 1.4986)
			(layers "F.Cu" "F.Mask" "F.Paste")
			(net "GND")
		)
		(pad "285" smd rect
			(at 2.050034 60.775088 270)
			(size 0.519938 1.4986)
			(layers "F.Cu" "F.Mask" "F.Paste")
			(net "M_C_CPU0_SB_DQ<30>")
		)
		(pad "286" smd rect
			(at 2.050034 61.624972 270)
			(size 0.519938 1.4986)
			(layers "F.Cu" "F.Mask" "F.Paste")
			(net "GND")
		)
		(pad "287" smd rect
			(at 2.050034 62.47511 270)
			(size 0.519938 1.4986)
			(layers "F.Cu" "F.Mask" "F.Paste")
			(net "M_C_CPU0_SB_DQ<31>")
		)
		(pad "288" smd rect
			(at 2.050034 63.324994 270)
			(size 0.519938 1.4986)
			(layers "F.Cu" "F.Mask" "F.Paste")
			(net "GND")
		)
		(pad "G1" thru_hole oval
			(at 0 -68.97497)
			(size 2.8194 1.5748)
			(drill oval 2.4384 1.1938)
			(layers "*.Cu" "*.Mask")
			(remove_unused_layers no)
			(net "GND")
			(clearance 0.127)
			(thermal_gap 0.127)
		)
		(pad "G2" thru_hole oval
			(at 0 3.875024)
			(size 2.8194 1.5748)
			(drill oval 2.4384 1.1938)
			(layers "*.Cu" "*.Mask")
			(remove_unused_layers no)
			(net "GND")
			(clearance 0.127)
			(thermal_gap 0.127)
		)
		(pad "G3" thru_hole oval
			(at 0 68.97497)
			(size 2.8194 1.5748)
			(drill oval 2.4384 1.1938)
			(layers "*.Cu" "*.Mask")
			(remove_unused_layers no)
			(net "GND")
			(clearance 0.127)
			(thermal_gap 0.127)
		)
	)
)
